# Stackup_F0T_Fan_BP_6L_1p6mm_IT-170GT_RTF_Rev0p1_20211021.xls — Special processing (pcb-stackup)
| Special processing : |  |
| Golden Finger(金手指) | Yes |
| VIPPO(Via in Pad樹脂填孔) | No |
| Back Drill(背鑽) with epoxy plug/fill | No |
| Back Drill(背鑽) without epoxy plug/fill | No |
| Laser Drill(HDI雷射鑽孔) | No |
| Low profile oxide(低棕化) | No |
